FILE_TYPE = CONNECTIVITY;
{Allegro Design Entry HDL 16.6-p007 (v16-6-112F) 10/10/2012}
"PAGE_NUMBER" = 100;
0"NC";
1"PVDDQ_KLM\g";
2"GND\g";
3"PVDDQ_GHJ\g";
4"PVDDQ_KLM\g";
5"GND\g";
6"GND\g";
7"PVDDQ_GHJ\g";
8"PVDDQ_KLM\g";
9"GND\g";
10"GND\g";
11"PVDDQ_GHJ\g";
12"GND\g";
13"M_G_VREF";
14"M_K_CPU_VREF";
15"M_G_CPU_VREF";
16"M_K_VREF";
17"M_H_CPU_VREF";
18"M_L_CPU_VREF";
19"M_L_VREF";
20"M_H_VREF";
21"M_M_CPU_VREF";
22"M_M_VREF";
23"M_J_CPU_VREF";
24"M_J_VREF";
%"PVDDQ_KLM"
"1","(-1900,2525)","0","mstr_symbols","I10";
;
VOLTAGE"1.2V"
CDS_LIB"mstr_symbols"
BODY_TYPE"PLUMBING"
HDL_POWER"PVDDQ_KLM";
"G\NAC"1;
%"RES"
"2","(-1900,2275)","2","mstr_discrete","I11";
;
CDS_SEC"1"
LOCATION"R9M1"
PART_NUMBER"G21796-026"
VALUE"1.00K"
TOLERANCE"1%"
PACK_TYPE"0402"
MATERIAL"CHIP"
WATTAGE"1/16W"
BOM_COST"SM_CONTROLLER"
CDS_LIB"mstr_discrete"
SEC_TYPE"0402"
SEC"1"
CDS_LOCATION"R9M1"
ROOM"MEM";
"A"
$PN"1"1;
"B"
$PN"2"16;
%"RES"
"1","(-2125,1950)","0","mstr_discrete","I13";
;
CDS_SEC"1"
LOCATION"R9M2"
PART_NUMBER"G21796-274"
VALUE"2"
TOLERANCE"1.0%"
PACK_TYPE"0402"
MATERIAL"CHIP"
WATTAGE"1/16W"
CDS_LIB"mstr_discrete"
SEC_TYPE"0402"
BOM_COST"PROC_SOCKET"
SEC"1"
CDS_LOCATION"R9M2"
ROOM"PROC";
"B"
$PN"2"16;
"A"
$PN"1"14;
%"GND"
"1","(-2125,1300)","0","mstr_symbols","I14";
;
VOLTAGE"0"
SIZE"1B"
CDS_LIB"mstr_symbols"
BODY_TYPE"PLUMBING"
HDL_POWER"GND";
"A\NAC"2;
%"CAP_A"
"1","(-2350,1650)","0","dev_discrete","I15";
;
LOCATION"C9M2"
PART_NUMBER"A36096-045"
VALUE"0.01UF"
TOLERANCE"10%"
PACK_TYPE"0402V"
VOLTAGE"25V"
MATERIAL"X7R"
CDS_LOCATION"C9M2"
BOM_COST"SM_CONTROLLER"
CDS_LIB"dev_discrete"
CDS_SEC"1"
SEC_TYPE"0402V"
SEC"1"
ROOM"MEM";
"B"
$PN"2"2;
"A"
$PN"1"14;
%"PVDDQ_GHJ"
"1","(450,4200)","0","mstr_symbols","I17";
;
VOLTAGE"1.2V"
CDS_LIB"mstr_symbols"
BODY_TYPE"PLUMBING"
HDL_POWER"PVDDQ_GHJ";
"G\NAC"3;
%"RES"
"2","(450,3950)","2","mstr_discrete","I19";
;
CDS_SEC"1"
VALUE"1.00K"
TOLERANCE"1%"
PACK_TYPE"0402"
MATERIAL"CHIP"
WATTAGE"1/16W"
LOCATION"R1G2"
PART_NUMBER"G21796-026"
SEC_TYPE"0402"
BOM_COST"SM_CONTROLLER"
CDS_LIB"mstr_discrete"
SEC"1"
CDS_LOCATION"R1G2"
ROOM"MEM";
"A"
$PN"1"3;
"B"
$PN"2"20;
%"RES"
"2","(-1825,3300)","2","mstr_discrete","I2";
;
CDS_SEC"1"
LOCATION"R1F6"
PART_NUMBER"G21796-026"
VALUE"1.00K"
TOLERANCE"1%"
PACK_TYPE"0402"
MATERIAL"CHIP"
WATTAGE"1/16W"
CDS_LIB"mstr_discrete"
BOM_COST"SM_CONTROLLER"
SEC_TYPE"0402"
SEC"1"
CDS_LOCATION"R1F6"
ROOM"MEM";
"A"
$PN"1"13;
"B"
$PN"2"12;
%"RES"
"2","(525,3300)","2","mstr_discrete","I20";
;
CDS_SEC"1"
LOCATION"R1G3"
PART_NUMBER"G21796-026"
VALUE"1.00K"
TOLERANCE"1%"
PACK_TYPE"0402"
MATERIAL"CHIP"
WATTAGE"1/16W"
SEC_TYPE"0402"
BOM_COST"SM_CONTROLLER"
CDS_LIB"mstr_discrete"
SEC"1"
CDS_LOCATION"R1G3"
ROOM"MEM";
"A"
$PN"1"20;
"B"
$PN"2"5;
%"PVDDQ_KLM"
"1","(450,2525)","0","mstr_symbols","I21";
;
VOLTAGE"1.2V"
CDS_LIB"mstr_symbols"
BODY_TYPE"PLUMBING"
HDL_POWER"PVDDQ_KLM";
"G\NAC"4;
%"RES"
"2","(450,2275)","2","mstr_discrete","I22";
;
CDS_SEC"1"
LOCATION"R9L7"
PART_NUMBER"G21796-026"
VALUE"1.00K"
TOLERANCE"1%"
PACK_TYPE"0402"
MATERIAL"CHIP"
WATTAGE"1/16W"
SEC_TYPE"0402"
CDS_LIB"mstr_discrete"
BOM_COST"SM_CONTROLLER"
SEC"1"
CDS_LOCATION"R9L7"
ROOM"MEM";
"A"
$PN"1"4;
"B"
$PN"2"19;
%"RES"
"2","(525,1625)","2","mstr_discrete","I24";
;
CDS_SEC"1"
LOCATION"R9L6"
PART_NUMBER"G21796-026"
VALUE"1.00K"
TOLERANCE"1%"
PACK_TYPE"0402"
MATERIAL"CHIP"
WATTAGE"1/16W"
SEC_TYPE"0402"
BOM_COST"PROC_SOCKET"
CDS_LIB"mstr_discrete"
SEC"1"
CDS_LOCATION"R9L6"
ROOM"PROC";
"A"
$PN"1"19;
"B"
$PN"2"6;
%"RES"
"1","(225,3625)","0","mstr_discrete","I25";
;
CDS_SEC"1"
LOCATION"R1G1"
PART_NUMBER"G21796-274"
VALUE"2"
TOLERANCE"1.0%"
PACK_TYPE"0402"
MATERIAL"CHIP"
WATTAGE"1/16W"
SEC_TYPE"0402"
CDS_LIB"mstr_discrete"
BOM_COST"PROC_SOCKET"
SEC"1"
CDS_LOCATION"R1G1"
ROOM"PROC";
"B"
$PN"2"20;
"A"
$PN"1"17;
%"CAP_A"
"1","(0,3325)","0","dev_discrete","I26";
;
LOCATION"C1G8"
PART_NUMBER"A36096-045"
VALUE"0.01UF"
TOLERANCE"10%"
PACK_TYPE"0402V"
VOLTAGE"25V"
MATERIAL"X7R"
CDS_LOCATION"C1G8"
BOM_COST"PROC_SOCKET"
CDS_LIB"dev_discrete"
CDS_SEC"1"
SEC_TYPE"0402V"
SEC"1"
ROOM"PROC";
"B"
$PN"2"5;
"A"
$PN"1"17;
%"GND"
"1","(225,2975)","0","mstr_symbols","I28";
;
VOLTAGE"0"
CDS_LIB"mstr_symbols"
SIZE"1B"
BODY_TYPE"PLUMBING"
HDL_POWER"GND";
"A\NAC"5;
%"RES"
"1","(225,1950)","0","mstr_discrete","I29";
;
CDS_SEC"1"
LOCATION"R9L8"
PART_NUMBER"G21796-274"
VALUE"2"
TOLERANCE"1.0%"
PACK_TYPE"0402"
MATERIAL"CHIP"
WATTAGE"1/16W"
BOM_COST"PROC_SOCKET"
SEC_TYPE"0402"
CDS_LIB"mstr_discrete"
SEC"1"
CDS_LOCATION"R9L8"
ROOM"PROC";
"B"
$PN"2"19;
"A"
$PN"1"18;
%"CAP_A"
"1","(0,1650)","0","dev_discrete","I30";
;
LOCATION"C9L8"
PART_NUMBER"A36096-045"
VALUE"0.01UF"
TOLERANCE"10%"
PACK_TYPE"0402V"
VOLTAGE"25V"
MATERIAL"X7R"
CDS_LOCATION"C9L8"
BOM_COST"SM_CONTROLLER"
CDS_LIB"dev_discrete"
CDS_SEC"1"
SEC_TYPE"0402V"
SEC"1"
ROOM"MEM";
"B"
$PN"2"6;
"A"
$PN"1"18;
%"GND"
"1","(225,1300)","0","mstr_symbols","I31";
;
VOLTAGE"0"
CDS_LIB"mstr_symbols"
SIZE"1B"
BODY_TYPE"PLUMBING"
HDL_POWER"GND";
"A\NAC"6;
%"PVDDQ_GHJ"
"1","(2900,4200)","0","mstr_symbols","I33";
;
VOLTAGE"1.2V"
CDS_LIB"mstr_symbols"
BODY_TYPE"PLUMBING"
HDL_POWER"PVDDQ_GHJ";
"G\NAC"7;
%"RES"
"2","(2900,3950)","2","mstr_discrete","I35";
;
CDS_SEC"1"
LOCATION"R1G15"
PART_NUMBER"G21796-026"
VALUE"1.00K"
TOLERANCE"1%"
PACK_TYPE"0402"
MATERIAL"CHIP"
WATTAGE"1/16W"
SEC_TYPE"0402"
BOM_COST"SM_CONTROLLER"
CDS_LIB"mstr_discrete"
SEC"1"
CDS_LOCATION"R1G15"
ROOM"MEM";
"A"
$PN"1"7;
"B"
$PN"2"24;
%"RES"
"2","(2975,3300)","2","mstr_discrete","I36";
;
CDS_SEC"1"
LOCATION"R1G17"
PART_NUMBER"G21796-026"
VALUE"1.00K"
TOLERANCE"1%"
PACK_TYPE"0402"
MATERIAL"CHIP"
WATTAGE"1/16W"
SEC_TYPE"0402"
BOM_COST"SM_CONTROLLER"
CDS_LIB"mstr_discrete"
SEC"1"
CDS_LOCATION"R1G17"
ROOM"MEM";
"A"
$PN"1"24;
"B"
$PN"2"9;
%"PVDDQ_KLM"
"1","(2900,2525)","0","mstr_symbols","I37";
;
VOLTAGE"1.2V"
CDS_LIB"mstr_symbols"
BODY_TYPE"PLUMBING"
HDL_POWER"PVDDQ_KLM";
"G\NAC"8;
%"RES"
"2","(2900,2275)","2","mstr_discrete","I38";
;
CDS_SEC"1"
LOCATION"R9L2"
PART_NUMBER"G21796-026"
VALUE"1.00K"
TOLERANCE"1%"
PACK_TYPE"0402"
MATERIAL"CHIP"
WATTAGE"1/16W"
SEC_TYPE"0402"
CDS_LIB"mstr_discrete"
BOM_COST"SM_CONTROLLER"
SEC"1"
CDS_LOCATION"R9L2"
ROOM"MEM";
"A"
$PN"1"8;
"B"
$PN"2"22;
%"RES"
"2","(-1825,1625)","2","mstr_discrete","I4";
;
CDS_SEC"1"
LOCATION"R9L11"
PART_NUMBER"G21796-026"
VALUE"1.00K"
TOLERANCE"1%"
PACK_TYPE"0402"
MATERIAL"CHIP"
WATTAGE"1/16W"
CDS_LIB"mstr_discrete"
BOM_COST"PROC_SOCKET"
SEC_TYPE"0402"
SEC"1"
CDS_LOCATION"R9L11"
ROOM"PROC";
"A"
$PN"1"16;
"B"
$PN"2"2;
%"RES"
"2","(2975,1625)","2","mstr_discrete","I40";
;
CDS_SEC"1"
LOCATION"R9L1"
PART_NUMBER"G21796-026"
TOLERANCE"1%"
PACK_TYPE"0402"
MATERIAL"CHIP"
WATTAGE"1/16W"
VALUE"1.00K"
SEC_TYPE"0402"
BOM_COST"PROC_SOCKET"
CDS_LIB"mstr_discrete"
SEC"1"
CDS_LOCATION"R9L1"
ROOM"PROC";
"A"
$PN"1"22;
"B"
$PN"2"10;
%"RES"
"1","(2675,3625)","0","mstr_discrete","I41";
;
CDS_SEC"1"
LOCATION"R1G14"
PART_NUMBER"G21796-274"
VALUE"2"
TOLERANCE"1.0%"
PACK_TYPE"0402"
MATERIAL"CHIP"
WATTAGE"1/16W"
SEC_TYPE"0402"
CDS_LIB"mstr_discrete"
BOM_COST"PROC_SOCKET"
SEC"1"
CDS_LOCATION"R1G14"
ROOM"PROC";
"B"
$PN"2"24;
"A"
$PN"1"23;
%"CAP_A"
"1","(2450,3325)","0","dev_discrete","I42";
;
LOCATION"C1G18"
PART_NUMBER"A36096-045"
VALUE"0.01UF"
TOLERANCE"10%"
PACK_TYPE"0402V"
VOLTAGE"25V"
MATERIAL"X7R"
CDS_LOCATION"C1G18"
BOM_COST"PROC_SOCKET"
CDS_LIB"dev_discrete"
CDS_SEC"1"
SEC_TYPE"0402V"
SEC"1"
ROOM"PROC";
"B"
$PN"2"9;
"A"
$PN"1"23;
%"GND"
"1","(2675,2975)","0","mstr_symbols","I44";
;
VOLTAGE"0"
CDS_LIB"mstr_symbols"
SIZE"1B"
BODY_TYPE"PLUMBING"
HDL_POWER"GND";
"A\NAC"9;
%"RES"
"1","(2675,1950)","0","mstr_discrete","I45";
;
CDS_SEC"1"
LOCATION"R9L3"
PART_NUMBER"G21796-274"
VALUE"2"
TOLERANCE"1.0%"
PACK_TYPE"0402"
MATERIAL"CHIP"
WATTAGE"1/16W"
BOM_COST"PROC_SOCKET"
SEC_TYPE"0402"
CDS_LIB"mstr_discrete"
SEC"1"
CDS_LOCATION"R9L3"
ROOM"PROC";
"B"
$PN"2"22;
"A"
$PN"1"21;
%"CAP_A"
"1","(2450,1650)","0","dev_discrete","I46";
;
LOCATION"C9L3"
PART_NUMBER"A36096-045"
VALUE"0.01UF"
TOLERANCE"10%"
PACK_TYPE"0402V"
VOLTAGE"25V"
MATERIAL"X7R"
CDS_LOCATION"C9L3"
BOM_COST"SM_CONTROLLER"
CDS_LIB"dev_discrete"
CDS_SEC"1"
SEC_TYPE"0402V"
SEC"1"
ROOM"MEM";
"B"
$PN"2"10;
"A"
$PN"1"21;
%"GND"
"1","(2675,1300)","0","mstr_symbols","I47";
;
VOLTAGE"0"
CDS_LIB"mstr_symbols"
SIZE"1B"
BODY_TYPE"PLUMBING"
HDL_POWER"GND";
"A\NAC"10;
%"PVDDQ_GHJ"
"1","(-1900,4200)","0","mstr_symbols","I5";
;
VOLTAGE"1.2V"
CDS_LIB"mstr_symbols"
BODY_TYPE"PLUMBING"
HDL_POWER"PVDDQ_GHJ";
"G\NAC"11;
%"RES"
"2","(-1900,3950)","2","mstr_discrete","I6";
;
CDS_SEC"1"
LOCATION"R1F5"
PART_NUMBER"G21796-026"
VALUE"1.00K"
TOLERANCE"1%"
PACK_TYPE"0402"
MATERIAL"CHIP"
WATTAGE"1/16W"
CDS_LIB"mstr_discrete"
BOM_COST"SM_CONTROLLER"
SEC_TYPE"0402"
SEC"1"
CDS_LOCATION"R1F5"
ROOM"MEM";
"A"
$PN"1"11;
"B"
$PN"2"13;
%"RES"
"1","(-2125,3625)","0","mstr_discrete","I7";
;
CDS_SEC"1"
LOCATION"R1F4"
PART_NUMBER"G21796-274"
VALUE"2"
TOLERANCE"1.0%"
PACK_TYPE"0402"
MATERIAL"CHIP"
WATTAGE"1/16W"
BOM_COST"PROC_SOCKET"
CDS_LIB"mstr_discrete"
SEC_TYPE"0402"
SEC"1"
CDS_LOCATION"R1F4"
ROOM"PROC";
"B"
$PN"2"13;
"A"
$PN"1"15;
%"CAP_A"
"1","(-2350,3325)","0","dev_discrete","I8";
;
LOCATION"C1F19"
PART_NUMBER"A36096-045"
VALUE"0.01UF"
TOLERANCE"10%"
PACK_TYPE"0402V"
VOLTAGE"25V"
MATERIAL"X7R"
CDS_LOCATION"C1F19"
BOM_COST"PROC_SOCKET"
CDS_LIB"dev_discrete"
CDS_SEC"1"
SEC_TYPE"0402V"
SEC"1"
ROOM"PROC";
"B"
$PN"2"12;
"A"
$PN"1"15;
%"GND"
"1","(-2125,2975)","0","mstr_symbols","I9";
;
VOLTAGE"0"
SIZE"1B"
CDS_LIB"mstr_symbols"
BODY_TYPE"PLUMBING"
HDL_POWER"GND";
"A\NAC"12;
END.
